(kicad_pcb
	(version 20221018)
	(generator pcbnew)
	(general
    (thickness 1.7403)
  )
	(paper "A4")
	(title_block
    (title "Data Center RDIMM DDR4 Tester")
    (date "2024-09-30")
    (rev "1.2.4")
		(comment 9 "footprints 599-606 of 690")
	)
	(layers
    (0 "F.Cu" signal)
    (1 "In1.Cu" power)
    (2 "In2.Cu" signal)
    (3 "In3.Cu" power)
    (4 "In4.Cu" power)
    (5 "In5.Cu" signal)
    (6 "In6.Cu" power)
    (7 "In7.Cu" signal)
    (8 "In8.Cu" power)
    (9 "In9.Cu" signal)
    (10 "In10.Cu" power)
    (31 "B.Cu" signal)
    (32 "B.Adhes" user "B.Adhesive")
    (33 "F.Adhes" user "F.Adhesive")
    (34 "B.Paste" user)
    (35 "F.Paste" user)
    (36 "B.SilkS" user "B.Silkscreen")
    (37 "F.SilkS" user "F.Silkscreen")
    (38 "B.Mask" user)
    (39 "F.Mask" user)
    (40 "Dwgs.User" user "User.Drawings")
    (41 "Cmts.User" user "User.Comments")
    (42 "Eco1.User" user "User.Eco1")
    (43 "Eco2.User" user "User.Eco2")
    (44 "Edge.Cuts" user)
    (45 "Margin" user)
    (46 "B.CrtYd" user "B.Courtyard")
    (47 "F.CrtYd" user "F.Courtyard")
    (48 "B.Fab" user)
    (49 "F.Fab" user)
  )
	(footprint "data-center-rdimm-ddr4-tester-footprints:C_2220_5650Metric" (layer "B.Cu")
    (at 195.05 120.05)
    (descr "Capacitor SMD 2220")
    (tags "capacitor SMD 2220")
    (property "Author" "Antmicro")
    (property "Dielectric" "")
    (property "License" "Apache-2.0")
    (property "MPN" "C5750X7S2A226M280KB")
    (property "Manufacturer" "TDK")
    (property "Sheetfile" "ethernet.kicad_sch")
    (property "Sheetname" "Ethernet")
    (property "Val" "22u/100V")
    (property "Voltage" "")
    (property "ki_description" " ")
    (attr smd)
    (fp_text reference "C224" (at 4.5 -1.39 270) (layer "B.SilkS")
        (effects (font (size 0.7 0.7) (thickness 0.15)) (justify left bottom mirror))
    )
    (fp_text value "C_22u_100V_2220" (at 0 -3.9 180) (layer "B.Fab") hide
        (effects (font (size 0.7 0.7) (thickness 0.15)) (justify left bottom mirror))
    )
    (fp_text user "${REFERENCE}" (at -3.7 -5.9 180) (layer "B.Fab") hide
        (effects (font (size 0.7 0.7) (thickness 0.15)) (justify left bottom mirror))
    )
    (fp_text user "License: Apache-2.0" (at -3.7 -6.9 180) (layer "B.Fab") hide
        (effects (font (size 0.7 0.7) (thickness 0.15)) (justify left bottom mirror))
    )
    (fp_text user "Author: Antmicro" (at -3.7 -7.9 180) (layer "B.Fab") hide
        (effects (font (size 0.7 0.7) (thickness 0.15)) (justify left bottom mirror))
    )
    (fp_line (start -1.415 -2.61) (end 1.415 -2.61)
      (stroke (width 0.15) (type solid)) (layer "B.SilkS"))
    (fp_line (start -1.415 2.61) (end 1.415 2.61)
      (stroke (width 0.15) (type solid)) (layer "B.SilkS"))
    (fp_rect (start -3.7 2.95) (end 3.7 -2.95)
      (stroke (width 0.05) (type solid)) (fill none) (layer "B.CrtYd"))
    (fp_rect (start -2.85 2.5) (end 2.85 -2.5)
      (stroke (width 0.15) (type solid)) (fill none) (layer "B.Fab"))
    (pad "1" smd roundrect (at -2.55 0) (size 1.8 5.4) (layers "B.Cu" "B.Paste" "B.Mask") (roundrect_rratio 0.138889)
      (net 360 "/Ethernet/VDD") (pintype "passive"))
    (pad "2" smd roundrect (at 2.55 0) (size 1.8 5.4) (layers "B.Cu" "B.Paste" "B.Mask") (roundrect_rratio 0.138889)
      (net 604 "GNDD") (pintype "passive"))
  )
	(footprint "data-center-rdimm-ddr4-tester-footprints:R_0402_1005Metric" (layer "B.Cu")
    (at 123.715 90.096)
    (descr "Resistor SMD 0402")
    (tags "resistor SMD 0402")
    (property "Author" "Antmicro")
    (property "License" "Apache-2.0")
    (property "MPN" "CR0402-FX-1002GLF")
    (property "Manufacturer" "Bourns")
    (property "Sheetfile" "supply.kicad_sch")
    (property "Sheetname" "Supply")
    (property "Tolerance" "1%")
    (property "Val" "10k")
    (property "ki_description" "10k resistor in 0402 package with 1% tolerance")
    (attr smd)
    (fp_text reference "R195" (at 1.205 1.614 180) (layer "B.SilkS")
        (effects (font (size 0.7 0.7) (thickness 0.15)) (justify left bottom mirror))
    )
    (fp_text value "R_10k_0402" (at 0 -1.4 180) (layer "B.Fab") hide
        (effects (font (size 0.7 0.7) (thickness 0.15)) (justify left bottom mirror))
    )
    (fp_text user "Author: Antmicro" (at -0.95 -4.169 180) (layer "B.Fab") hide
        (effects (font (size 0.7 0.7) (thickness 0.15)) (justify left bottom mirror))
    )
    (fp_text user "${REFERENCE}" (at -0.95 -3.168 180) (layer "B.Fab") hide
        (effects (font (size 0.7 0.7) (thickness 0.15)) (justify left bottom mirror))
    )
    (fp_text user "License: Apache-2.0" (at -0.95 -5.169 180) (layer "B.Fab") hide
        (effects (font (size 0.7 0.7) (thickness 0.15)) (justify left bottom mirror))
    )
    (fp_rect (start -0.93 0.47) (end 0.93 -0.47)
      (stroke (width 0.05) (type solid)) (fill none) (layer "B.CrtYd"))
    (fp_rect (start -0.5 0.25) (end 0.5 -0.25)
      (stroke (width 0.15) (type solid)) (fill none) (layer "B.Fab"))
    (pad "1" smd roundrect (at -0.485 0) (size 0.59 0.64) (layers "B.Cu" "B.Paste" "B.Mask") (roundrect_rratio 0.25)
      (net 143 "3V3_SYS") (pintype "passive"))
    (pad "2" smd roundrect (at 0.485 0) (size 0.59 0.64) (layers "B.Cu" "B.Paste" "B.Mask") (roundrect_rratio 0.25)
      (net 661 "Net-(U20-~{PWRDN})") (pintype "passive"))
  )
	(footprint "data-center-rdimm-ddr4-tester-footprints:C_0201" (layer "B.Cu")
    (at 194.35 91.5 180)
    (descr "Capacitor SMD 0201")
    (tags "capacitor SMD 0201")
    (property "Author" "Antmicro")
    (property "Dielectric" "")
    (property "License" "Apache-2.0")
    (property "MPN" "CC0201KRX6S5BB104")
    (property "Manufacturer" "Yaego")
    (property "Sheetfile" "fpga-power.kicad_sch")
    (property "Sheetname" "FPGA power")
    (property "Val" "100n")
    (property "Voltage" "")
    (property "ki_description" " ")
    (attr smd)
    (fp_text reference "C254" (at -4.39 -0.2) (layer "B.SilkS")
        (effects (font (size 0.7 0.7) (thickness 0.15)) (justify left bottom mirror))
    )
    (fp_text value "C_100n_0201" (at 0 -1.4) (layer "B.Fab") hide
        (effects (font (size 0.7 0.7) (thickness 0.15)) (justify left bottom mirror))
    )
    (fp_text user "${REFERENCE}" (at -0.72 -3.4) (layer "B.Fab") hide
        (effects (font (size 0.7 0.7) (thickness 0.15)) (justify left bottom mirror))
    )
    (fp_text user "License: Apache-2.0" (at -0.72 -4.4) (layer "B.Fab") hide
        (effects (font (size 0.7 0.7) (thickness 0.15)) (justify left bottom mirror))
    )
    (fp_text user "Author: Antmicro" (at -0.72 -5.4) (layer "B.Fab") hide
        (effects (font (size 0.7 0.7) (thickness 0.15)) (justify left bottom mirror))
    )
    (fp_rect (start -0.72 0.38) (end 0.72 -0.38)
      (stroke (width 0.05) (type solid)) (fill none) (layer "B.CrtYd"))
    (fp_rect (start 0.3 -0.15) (end -0.301 0.149)
      (stroke (width 0.15) (type solid)) (fill none) (layer "B.Fab"))
    (pad "" smd roundrect (at -0.349 0.002 180) (size 0.318 0.36) (layers "B.Paste") (roundrect_rratio 0.25))
    (pad "" smd roundrect (at 0.341 0.002 180) (size 0.318 0.36) (layers "B.Paste") (roundrect_rratio 0.25))
    (pad "1" smd roundrect (at -0.321 0.002 180) (size 0.46 0.4) (layers "B.Cu" "B.Mask") (roundrect_rratio 0.25)
      (net 306 "1V2_SYS") (pintype "passive"))
    (pad "2" smd roundrect (at 0.32 0.002 180) (size 0.46 0.4) (layers "B.Cu" "B.Mask") (roundrect_rratio 0.25)
      (net 9 "GND") (pintype "passive"))
  )
	(footprint "data-center-rdimm-ddr4-tester-footprints:C_0201" (layer "B.Cu")
    (at 193.2 87.375)
    (descr "Capacitor SMD 0201")
    (tags "capacitor SMD 0201")
    (property "Author" "Antmicro")
    (property "Dielectric" "")
    (property "License" "Apache-2.0")
    (property "MPN" "CC0201KRX6S5BB104")
    (property "Manufacturer" "Yaego")
    (property "Sheetfile" "fpga-power.kicad_sch")
    (property "Sheetname" "FPGA power")
    (property "Val" "100n")
    (property "Voltage" "")
    (property "ki_description" " ")
    (attr smd)
    (fp_text reference "C300" (at 3.52 0.365 180) (layer "B.SilkS")
        (effects (font (size 0.7 0.7) (thickness 0.15)) (justify left bottom mirror))
    )
    (fp_text value "C_100n_0201" (at 0 -1.4 180) (layer "B.Fab") hide
        (effects (font (size 0.7 0.7) (thickness 0.15)) (justify left bottom mirror))
    )
    (fp_text user "${REFERENCE}" (at -0.72 -3.4 180) (layer "B.Fab") hide
        (effects (font (size 0.7 0.7) (thickness 0.15)) (justify left bottom mirror))
    )
    (fp_text user "Author: Antmicro" (at -0.72 -5.4 180) (layer "B.Fab") hide
        (effects (font (size 0.7 0.7) (thickness 0.15)) (justify left bottom mirror))
    )
    (fp_text user "License: Apache-2.0" (at -0.72 -4.4 180) (layer "B.Fab") hide
        (effects (font (size 0.7 0.7) (thickness 0.15)) (justify left bottom mirror))
    )
    (fp_rect (start -0.72 0.38) (end 0.72 -0.38)
      (stroke (width 0.05) (type solid)) (fill none) (layer "B.CrtYd"))
    (fp_rect (start 0.3 -0.15) (end -0.301 0.149)
      (stroke (width 0.15) (type solid)) (fill none) (layer "B.Fab"))
    (pad "" smd roundrect (at -0.349 0.002) (size 0.318 0.36) (layers "B.Paste") (roundrect_rratio 0.25))
    (pad "" smd roundrect (at 0.341 0.002) (size 0.318 0.36) (layers "B.Paste") (roundrect_rratio 0.25))
    (pad "1" smd roundrect (at -0.321 0.002) (size 0.46 0.4) (layers "B.Cu" "B.Mask") (roundrect_rratio 0.25)
      (net 143 "3V3_SYS") (pintype "passive"))
    (pad "2" smd roundrect (at 0.32 0.002) (size 0.46 0.4) (layers "B.Cu" "B.Mask") (roundrect_rratio 0.25)
      (net 9 "GND") (pintype "passive"))
  )
	(footprint "data-center-rdimm-ddr4-tester-footprints:C_0201" (layer "B.Cu")
    (at 175.325 84.675 180)
    (descr "Capacitor SMD 0201")
    (tags "capacitor SMD 0201")
    (property "Author" "Antmicro")
    (property "Dielectric" "")
    (property "License" "Apache-2.0")
    (property "MPN" "CC0201KRX6S5BB104")
    (property "Manufacturer" "Yaego")
    (property "Sheetfile" "fpga-power.kicad_sch")
    (property "Sheetname" "FPGA power")
    (property "Val" "100n")
    (property "Voltage" "")
    (property "ki_description" " ")
    (attr smd)
    (fp_text reference "C298" (at -0.865 0.475) (layer "B.SilkS")
        (effects (font (size 0.7 0.7) (thickness 0.15)) (justify left bottom mirror))
    )
    (fp_text value "C_100n_0201" (at 0 -1.4) (layer "B.Fab") hide
        (effects (font (size 0.7 0.7) (thickness 0.15)) (justify left bottom mirror))
    )
    (fp_text user "License: Apache-2.0" (at -0.72 -4.4) (layer "B.Fab") hide
        (effects (font (size 0.7 0.7) (thickness 0.15)) (justify left bottom mirror))
    )
    (fp_text user "${REFERENCE}" (at -0.72 -3.4) (layer "B.Fab") hide
        (effects (font (size 0.7 0.7) (thickness 0.15)) (justify left bottom mirror))
    )
    (fp_text user "Author: Antmicro" (at -0.72 -5.4) (layer "B.Fab") hide
        (effects (font (size 0.7 0.7) (thickness 0.15)) (justify left bottom mirror))
    )
    (fp_rect (start -0.72 0.38) (end 0.72 -0.38)
      (stroke (width 0.05) (type solid)) (fill none) (layer "B.CrtYd"))
    (fp_rect (start 0.3 -0.15) (end -0.301 0.149)
      (stroke (width 0.15) (type solid)) (fill none) (layer "B.Fab"))
    (pad "" smd roundrect (at -0.349 0.002 180) (size 0.318 0.36) (layers "B.Paste") (roundrect_rratio 0.25))
    (pad "" smd roundrect (at 0.341 0.002 180) (size 0.318 0.36) (layers "B.Paste") (roundrect_rratio 0.25))
    (pad "1" smd roundrect (at -0.321 0.002 180) (size 0.46 0.4) (layers "B.Cu" "B.Mask") (roundrect_rratio 0.25)
      (net 143 "3V3_SYS") (pintype "passive"))
    (pad "2" smd roundrect (at 0.32 0.002 180) (size 0.46 0.4) (layers "B.Cu" "B.Mask") (roundrect_rratio 0.25)
      (net 9 "GND") (pintype "passive"))
  )
	(footprint "data-center-rdimm-ddr4-tester-footprints:C_0201" (layer "B.Cu")
    (at 178.05 92.225 -90)
    (descr "Capacitor SMD 0201")
    (tags "capacitor SMD 0201")
    (property "Author" "Antmicro")
    (property "Dielectric" "")
    (property "License" "Apache-2.0")
    (property "MPN" "CC0201KRX6S5BB104")
    (property "Manufacturer" "Yaego")
    (property "Sheetfile" "fpga-power.kicad_sch")
    (property "Sheetname" "FPGA power")
    (property "Val" "100n")
    (property "Voltage" "")
    (property "ki_description" " ")
    (attr smd)
    (fp_text reference "C301" (at -1.265 0.51 90) (layer "B.SilkS")
        (effects (font (size 0.7 0.7) (thickness 0.15)) (justify left bottom mirror))
    )
    (fp_text value "C_100n_0201" (at 0 -1.4 90) (layer "B.Fab") hide
        (effects (font (size 0.7 0.7) (thickness 0.15)) (justify left bottom mirror))
    )
    (fp_text user "License: Apache-2.0" (at -0.72 -4.4 90) (layer "B.Fab") hide
        (effects (font (size 0.7 0.7) (thickness 0.15)) (justify left bottom mirror))
    )
    (fp_text user "Author: Antmicro" (at -0.72 -5.4 90) (layer "B.Fab") hide
        (effects (font (size 0.7 0.7) (thickness 0.15)) (justify left bottom mirror))
    )
    (fp_text user "${REFERENCE}" (at -0.72 -3.4 90) (layer "B.Fab") hide
        (effects (font (size 0.7 0.7) (thickness 0.15)) (justify left bottom mirror))
    )
    (fp_rect (start -0.72 0.38) (end 0.72 -0.38)
      (stroke (width 0.05) (type solid)) (fill none) (layer "B.CrtYd"))
    (fp_rect (start 0.3 -0.15) (end -0.301 0.149)
      (stroke (width 0.15) (type solid)) (fill none) (layer "B.Fab"))
    (pad "" smd roundrect (at -0.349 0.002 270) (size 0.318 0.36) (layers "B.Paste") (roundrect_rratio 0.25))
    (pad "" smd roundrect (at 0.341 0.002 270) (size 0.318 0.36) (layers "B.Paste") (roundrect_rratio 0.25))
    (pad "1" smd roundrect (at -0.321 0.002 270) (size 0.46 0.4) (layers "B.Cu" "B.Mask") (roundrect_rratio 0.25)
      (net 143 "3V3_SYS") (pintype "passive"))
    (pad "2" smd roundrect (at 0.32 0.002 270) (size 0.46 0.4) (layers "B.Cu" "B.Mask") (roundrect_rratio 0.25)
      (net 9 "GND") (pintype "passive"))
  )
	(footprint "data-center-rdimm-ddr4-tester-footprints:SOIC-4_4.55x2.6mm_P1.27" (layer "B.Cu")
    (at 164.5 133.525)
    (descr "ACPL-217-500E")
    (tags "Integrated Circuit")
    (property "Author" "Antmicro")
    (property "Description" "Broadcom ACPL-217-500E DC Input Transistor Output Optocoupler, Surface Mount, 4-Pin SO")
    (property "License" "Apache-2.0")
    (property "MPN" "ACPL-217-500E")
    (property "Manufacturer" "Broadcom")
    (property "Sheetfile" "ethernet.kicad_sch")
    (property "Sheetname" "Ethernet")
    (property "ki_description" "Broadcom ACPL-217-500E DC Input Transistor Output Optocoupler, Surface Mount, 4-Pin SO")
    (attr smd)
    (fp_text reference "IC2" (at 0 -1.695 180) (layer "B.SilkS")
        (effects (font (size 0.7 0.7) (thickness 0.15)) (justify left bottom mirror))
    )
    (fp_text value "ACPL-217-500E" (at -4.25 -2.75 180) (layer "B.Fab") hide
        (effects (font (size 0.7 0.7) (thickness 0.15)) (justify left bottom mirror))
    )
    (fp_text user "." (at -2.7 1.6 180) (layer "B.SilkS")
        (effects (font (size 1 1) (thickness 0.15)) (justify mirror))
    )
    (fp_text user "${REFERENCE}" (at -4.3 -4.25 180) (layer "B.Fab") hide
        (effects (font (size 0.7 0.7) (thickness 0.15)) (justify left bottom mirror))
    )
    (fp_text user "License: Apache-2.0" (at -4.25 -7 180) (layer "B.Fab") hide
        (effects (font (size 0.7 0.7) (thickness 0.15)) (justify left bottom mirror))
    )
    (fp_text user "Author: Antmicro" (at -4.3 -5.5 180) (layer "B.Fab") hide
        (effects (font (size 0.7 0.7) (thickness 0.15)) (justify left bottom mirror))
    )
    (fp_line (start -2.3 -1.1) (end -2.3 -1.4)
      (stroke (width 0.12) (type solid)) (layer "B.SilkS"))
    (fp_line (start -2.3 1.4) (end -1.8 1.4)
      (stroke (width 0.12) (type solid)) (layer "B.SilkS"))
    (fp_line (start -1.8 -1.4) (end -2.3 -1.4)
      (stroke (width 0.12) (type solid)) (layer "B.SilkS"))
    (fp_line (start 1.8 1.4) (end 2.3 1.4)
      (stroke (width 0.12) (type solid)) (layer "B.SilkS"))
    (fp_line (start 2.3 -1.4) (end 1.8 -1.4)
      (stroke (width 0.12) (type solid)) (layer "B.SilkS"))
    (fp_line (start 2.3 -1.1) (end 2.3 -1.4)
      (stroke (width 0.12) (type solid)) (layer "B.SilkS"))
    (fp_line (start 2.3 1.1) (end 2.3 1.4)
      (stroke (width 0.12) (type solid)) (layer "B.SilkS"))
    (fp_line (start -4.3 -1.69) (end -4.3 1.7)
      (stroke (width 0.05) (type solid)) (layer "B.CrtYd"))
    (fp_line (start -4.3 1.7) (end 4.29 1.7)
      (stroke (width 0.05) (type solid)) (layer "B.CrtYd"))
    (fp_line (start 4.29 -1.69) (end -4.3 -1.69)
      (stroke (width 0.05) (type solid)) (layer "B.CrtYd"))
    (fp_line (start 4.29 1.7) (end 4.29 -1.69)
      (stroke (width 0.05) (type solid)) (layer "B.CrtYd"))
    (fp_line (start -2.201 -1.3) (end -2.201 1.301)
      (stroke (width 0.15) (type solid)) (layer "B.Fab"))
    (fp_line (start -2.201 0.03) (end -0.931 1.301)
      (stroke (width 0.15) (type solid)) (layer "B.Fab"))
    (fp_line (start -2.201 1.301) (end 2.2 1.301)
      (stroke (width 0.15) (type solid)) (layer "B.Fab"))
    (fp_line (start 2.2 -1.3) (end -2.201 -1.3)
      (stroke (width 0.15) (type solid)) (layer "B.Fab"))
    (fp_line (start 2.2 1.301) (end 2.2 -1.3)
      (stroke (width 0.15) (type solid)) (layer "B.Fab"))
    (pad "1" smd roundrect (at -3.125 0.635 270) (size 0.65 1.85) (layers "B.Cu" "B.Paste" "B.Mask") (roundrect_rratio 0.15)
      (net 626 "VIN_RAW") (pintype "passive"))
    (pad "2" smd roundrect (at -3.125 -0.634 270) (size 0.65 1.85) (layers "B.Cu" "B.Paste" "B.Mask") (roundrect_rratio 0.15)
      (net 628 "Net-(IC2-Pad2)") (pintype "passive"))
    (pad "3" smd roundrect (at 3.124 -0.634 270) (size 0.65 1.85) (layers "B.Cu" "B.Paste" "B.Mask") (roundrect_rratio 0.15)
      (net 627 "Net-(IC2-Pad3)") (pintype "passive"))
    (pad "4" smd roundrect (at 3.124 0.635 270) (size 0.65 1.85) (layers "B.Cu" "B.Paste" "B.Mask") (roundrect_rratio 0.15)
      (net 615 "/Ethernet/POE_ACTIVE") (pintype "passive"))
  )
	(footprint "data-center-rdimm-ddr4-tester-footprints:R_0402_1005Metric" (layer "B.Cu")
    (at 138.96 98.72 -90)
    (descr "Resistor SMD 0402")
    (tags "resistor SMD 0402")
    (property "Author" "Antmicro")
    (property "License" "Apache-2.0")
    (property "MPN" "CR0402-FX-1003GLF")
    (property "Manufacturer" "Bourns")
    (property "Sheetfile" "supply.kicad_sch")
    (property "Sheetname" "Supply")
    (property "Tolerance" "1%")
    (property "Val" "100k")
    (property "ki_description" "100k resistor in 0402 package with 1% tolerance")
    (attr smd)
    (fp_text reference "R215" (at -1.32 -1.44 90) (layer "B.SilkS")
        (effects (font (size 0.7 0.7) (thickness 0.15)) (justify left bottom mirror))
    )
    (fp_text value "R_100k_0402" (at 0 -1.4 90) (layer "B.Fab") hide
        (effects (font (size 0.7 0.7) (thickness 0.15)) (justify left bottom mirror))
    )
    (fp_text user "Author: Antmicro" (at -0.95 -4.169 90) (layer "B.Fab") hide
        (effects (font (size 0.7 0.7) (thickness 0.15)) (justify left bottom mirror))
    )
    (fp_text user "License: Apache-2.0" (at -0.95 -5.169 90) (layer "B.Fab") hide
        (effects (font (size 0.7 0.7) (thickness 0.15)) (justify left bottom mirror))
    )
    (fp_text user "${REFERENCE}" (at -0.95 -3.168 90) (layer "B.Fab") hide
        (effects (font (size 0.7 0.7) (thickness 0.15)) (justify left bottom mirror))
    )
    (fp_rect (start -0.93 0.47) (end 0.93 -0.47)
      (stroke (width 0.05) (type solid)) (fill none) (layer "B.CrtYd"))
    (fp_rect (start -0.5 0.25) (end 0.5 -0.25)
      (stroke (width 0.15) (type solid)) (fill none) (layer "B.Fab"))
    (pad "1" smd roundrect (at -0.485 0 270) (size 0.59 0.64) (layers "B.Cu" "B.Paste" "B.Mask") (roundrect_rratio 0.25)
      (net 9 "GND") (pintype "passive"))
    (pad "2" smd roundrect (at 0.485 0 270) (size 0.59 0.64) (layers "B.Cu" "B.Paste" "B.Mask") (roundrect_rratio 0.25)
      (net 800 "FPGA_VTT_CNTL") (pintype "passive"))
  )
)
